(kicad_pcb
	(version 20240108)
	(generator "pcbnew")
	(generator_version "8.0")
	(general
		(thickness 1.62)
		(legacy_teardrops no)
	)
	(paper "A4")
	(title_block
		(title "Jetson Orin Baseboard")
		(date "2025-03-12")
		(rev "1.3.4")
		(company "Antmicro Ltd")
		(comment 1 "www.antmicro.com")
		(comment 9 "footprints 75-79 of 677")
	)
	(layers
		(0 "F.Cu" signal)
		(1 "In1.Cu" signal)
		(2 "In2.Cu" signal)
		(3 "In3.Cu" signal)
		(4 "In4.Cu" jumper)
		(5 "In5.Cu" signal)
		(6 "In6.Cu" signal)
		(31 "B.Cu" signal)
		(32 "B.Adhes" user "B.Adhesive")
		(33 "F.Adhes" user "F.Adhesive")
		(34 "B.Paste" user)
		(35 "F.Paste" user)
		(36 "B.SilkS" user "B.Silkscreen")
		(37 "F.SilkS" user "F.Silkscreen")
		(38 "B.Mask" user)
		(39 "F.Mask" user)
		(40 "Dwgs.User" user "User.Drawings")
		(41 "Cmts.User" user "User.Comments")
		(42 "Eco1.User" user "User.Eco1")
		(43 "Eco2.User" user "User.Eco2")
		(44 "Edge.Cuts" user)
		(45 "Margin" user)
		(46 "B.CrtYd" user "B.Courtyard")
		(47 "F.CrtYd" user "F.Courtyard")
		(48 "B.Fab" user)
		(49 "F.Fab" user)
	)
	(footprint "antmicro-footprints:R_0402_1005Metric"
		(layer "F.Cu")
		(at 103.2 115.8 90)
		(descr "Resistor SMD 0402")
		(tags "resistor SMD 0402")
		(property "Reference" "R137"
			(at 0.9 0.45 90)
			(layer "F.SilkS")
			(effects
				(font
					(size 0.7 0.7)
					(thickness 0.15)
				)
				(justify left bottom)
			)
		)
		(property "Value" "R_10k_0402"
			(at 0 1.4 90)
			(layer "F.Fab")
			(effects
				(font
					(size 0.7 0.7)
					(thickness 0.15)
				)
				(justify left bottom)
			)
		)
		(property "Footprint" "antmicro-footprints:R_0402_1005Metric"
			(at 0 0 90)
			(layer "F.Fab")
			(hide yes)
			(effects
				(font
					(size 1.27 1.27)
					(thickness 0.15)
				)
			)
		)
		(property "Datasheet" "https://www.bourns.com/docs/product-datasheets/cr.pdf"
			(at 0 0 90)
			(layer "F.Fab")
			(hide yes)
			(effects
				(font
					(size 1.27 1.27)
					(thickness 0.15)
				)
			)
		)
		(property "Author" "Antmicro"
			(at 219 12.6 0)
			(layer "F.Fab")
			(hide yes)
			(effects
				(font
					(size 1 1)
					(thickness 0.15)
				)
			)
		)
		(property "License" "Apache-2.0"
			(at 219 12.6 0)
			(layer "F.Fab")
			(hide yes)
			(effects
				(font
					(size 1 1)
					(thickness 0.15)
				)
			)
		)
		(property "MPN" "CR0402-FX-1002GLF"
			(at 219 12.6 0)
			(layer "F.Fab")
			(hide yes)
			(effects
				(font
					(size 1 1)
					(thickness 0.15)
				)
			)
		)
		(property "Manufacturer" "Bourns"
			(at 219 12.6 0)
			(layer "F.Fab")
			(hide yes)
			(effects
				(font
					(size 1 1)
					(thickness 0.15)
				)
			)
		)
		(property "Tolerance" "1%"
			(at 219 12.6 0)
			(layer "F.Fab")
			(hide yes)
			(effects
				(font
					(size 1 1)
					(thickness 0.15)
				)
			)
		)
		(property "Val" "10k"
			(at 219 12.6 0)
			(layer "F.Fab")
			(hide yes)
			(effects
				(font
					(size 1 1)
					(thickness 0.15)
				)
			)
		)
		(sheetname "USB3")
		(sheetfile "usb3.kicad_sch")
		(attr smd)
		(fp_rect
			(start -0.925 -0.47)
			(end 0.925 0.47)
			(stroke
				(width 0.05)
				(type default)
			)
			(fill none)
			(layer "F.CrtYd")
		)
		(fp_rect
			(start -0.5 -0.25)
			(end 0.5 0.25)
			(stroke
				(width 0.15)
				(type solid)
			)
			(fill none)
			(layer "F.Fab")
		)
		(fp_text user "License: Apache-2.0"
			(at -0.95 5.169 90)
			(layer "F.Fab")
			(hide yes)
			(effects
				(font
					(size 0.7 0.7)
					(thickness 0.15)
				)
				(justify left bottom)
			)
		)
		(fp_text user "Author: Antmicro"
			(at -0.95 4.169 90)
			(layer "F.Fab")
			(hide yes)
			(effects
				(font
					(size 0.7 0.7)
					(thickness 0.15)
				)
				(justify left bottom)
			)
		)
		(fp_text user "${REFERENCE}"
			(at -0.95 3.168 90)
			(layer "F.Fab")
			(hide yes)
			(effects
				(font
					(size 0.7 0.7)
					(thickness 0.15)
				)
				(justify left bottom)
			)
		)
		(pad "1" smd roundrect
			(at -0.48 0 90)
			(size 0.59 0.64)
			(layers "F.Cu" "F.Paste" "F.Mask")
			(roundrect_rratio 0.25)
			(net 625 "Net-(Q4-D)")
			(pintype "passive")
		)
		(pad "2" smd roundrect
			(at 0.48 0 90)
			(size 0.59 0.64)
			(layers "F.Cu" "F.Paste" "F.Mask")
			(roundrect_rratio 0.25)
			(net 562 "USBC1_PEN")
			(pintype "passive")
		)
	)
	(footprint "antmicro-footprints:R_0402_1005Metric"
		(layer "F.Cu")
		(at 129.9 107.9 -90)
		(descr "Resistor SMD 0402")
		(tags "resistor SMD 0402")
		(property "Reference" "R39"
			(at 3.85 -0.37 -90)
			(layer "F.SilkS")
			(effects
				(font
					(size 0.7 0.7)
					(thickness 0.15)
				)
				(justify left bottom)
			)
		)
		(property "Value" "R_200R_0402"
			(at 0 1.4 -90)
			(layer "F.Fab")
			(effects
				(font
					(size 0.7 0.7)
					(thickness 0.15)
				)
				(justify left bottom)
			)
		)
		(property "Footprint" "antmicro-footprints:R_0402_1005Metric"
			(at 0 0 -90)
			(layer "F.Fab")
			(hide yes)
			(effects
				(font
					(size 1.27 1.27)
					(thickness 0.15)
				)
			)
		)
		(property "Datasheet" "https://www.bourns.com/docs/product-datasheets/cr.pdf"
			(at 0 0 -90)
			(layer "F.Fab")
			(hide yes)
			(effects
				(font
					(size 1.27 1.27)
					(thickness 0.15)
				)
			)
		)
		(property "Author" "Antmicro"
			(at 22 237.8 0)
			(layer "F.Fab")
			(hide yes)
			(effects
				(font
					(size 1 1)
					(thickness 0.15)
				)
			)
		)
		(property "License" "Apache-2.0"
			(at 22 237.8 0)
			(layer "F.Fab")
			(hide yes)
			(effects
				(font
					(size 1 1)
					(thickness 0.15)
				)
			)
		)
		(property "MPN" "CR0402-FX-2000GLF"
			(at 22 237.8 0)
			(layer "F.Fab")
			(hide yes)
			(effects
				(font
					(size 1 1)
					(thickness 0.15)
				)
			)
		)
		(property "Manufacturer" "Bourns"
			(at 22 237.8 0)
			(layer "F.Fab")
			(hide yes)
			(effects
				(font
					(size 1 1)
					(thickness 0.15)
				)
			)
		)
		(property "Tolerance" "1%"
			(at 22 237.8 0)
			(layer "F.Fab")
			(hide yes)
			(effects
				(font
					(size 1 1)
					(thickness 0.15)
				)
			)
		)
		(property "Val" "200R"
			(at 22 237.8 0)
			(layer "F.Fab")
			(hide yes)
			(effects
				(font
					(size 1 1)
					(thickness 0.15)
				)
			)
		)
		(sheetname "M.2")
		(sheetfile "m-2.kicad_sch")
		(attr smd)
		(fp_rect
			(start -0.925 -0.47)
			(end 0.925 0.47)
			(stroke
				(width 0.05)
				(type default)
			)
			(fill none)
			(layer "F.CrtYd")
		)
		(fp_rect
			(start -0.5 -0.25)
			(end 0.5 0.25)
			(stroke
				(width 0.15)
				(type solid)
			)
			(fill none)
			(layer "F.Fab")
		)
		(fp_text user "${REFERENCE}"
			(at -0.95 3.168 -90)
			(layer "F.Fab")
			(hide yes)
			(effects
				(font
					(size 0.7 0.7)
					(thickness 0.15)
				)
				(justify left bottom)
			)
		)
		(fp_text user "Author: Antmicro"
			(at -0.95 4.169 -90)
			(layer "F.Fab")
			(hide yes)
			(effects
				(font
					(size 0.7 0.7)
					(thickness 0.15)
				)
				(justify left bottom)
			)
		)
		(fp_text user "License: Apache-2.0"
			(at -0.95 5.169 -90)
			(layer "F.Fab")
			(hide yes)
			(effects
				(font
					(size 0.7 0.7)
					(thickness 0.15)
				)
				(justify left bottom)
			)
		)
		(pad "1" smd roundrect
			(at -0.48 0 270)
			(size 0.59 0.64)
			(layers "F.Cu" "F.Paste" "F.Mask")
			(roundrect_rratio 0.25)
			(net 141 "Net-(D1-A)")
			(pintype "passive")
		)
		(pad "2" smd roundrect
			(at 0.48 0 270)
			(size 0.59 0.64)
			(layers "F.Cu" "F.Paste" "F.Mask")
			(roundrect_rratio 0.25)
			(net 87 "+3V3")
			(pintype "passive")
		)
	)
	(footprint "antmicro-footprints:R_0402_1005Metric"
		(layer "F.Cu")
		(at 105.15 104.1 180)
		(descr "Resistor SMD 0402")
		(tags "resistor SMD 0402")
		(property "Reference" "R116"
			(at 3.65 -0.4 180)
			(layer "F.SilkS")
			(effects
				(font
					(size 0.7 0.7)
					(thickness 0.15)
				)
				(justify left bottom)
			)
		)
		(property "Value" "R_10k_0402"
			(at 0 1.4 180)
			(layer "F.Fab")
			(effects
				(font
					(size 0.7 0.7)
					(thickness 0.15)
				)
				(justify left bottom)
			)
		)
		(property "Footprint" "antmicro-footprints:R_0402_1005Metric"
			(at 0 0 180)
			(layer "F.Fab")
			(hide yes)
			(effects
				(font
					(size 1.27 1.27)
					(thickness 0.15)
				)
			)
		)
		(property "Datasheet" "https://www.bourns.com/docs/product-datasheets/cr.pdf"
			(at 0 0 180)
			(layer "F.Fab")
			(hide yes)
			(effects
				(font
					(size 1.27 1.27)
					(thickness 0.15)
				)
			)
		)
		(property "Author" "Antmicro"
			(at 210.3 208.2 0)
			(layer "F.Fab")
			(hide yes)
			(effects
				(font
					(size 1 1)
					(thickness 0.15)
				)
			)
		)
		(property "License" "Apache-2.0"
			(at 210.3 208.2 0)
			(layer "F.Fab")
			(hide yes)
			(effects
				(font
					(size 1 1)
					(thickness 0.15)
				)
			)
		)
		(property "MPN" "CR0402-FX-1002GLF"
			(at 210.3 208.2 0)
			(layer "F.Fab")
			(hide yes)
			(effects
				(font
					(size 1 1)
					(thickness 0.15)
				)
			)
		)
		(property "Manufacturer" "Bourns"
			(at 210.3 208.2 0)
			(layer "F.Fab")
			(hide yes)
			(effects
				(font
					(size 1 1)
					(thickness 0.15)
				)
			)
		)
		(property "Tolerance" "1%"
			(at 210.3 208.2 0)
			(layer "F.Fab")
			(hide yes)
			(effects
				(font
					(size 1 1)
					(thickness 0.15)
				)
			)
		)
		(property "Val" "10k"
			(at 210.3 208.2 0)
			(layer "F.Fab")
			(hide yes)
			(effects
				(font
					(size 1 1)
					(thickness 0.15)
				)
			)
		)
		(sheetname "USB3")
		(sheetfile "usb3.kicad_sch")
		(attr smd)
		(fp_rect
			(start -0.925 -0.47)
			(end 0.925 0.47)
			(stroke
				(width 0.05)
				(type default)
			)
			(fill none)
			(layer "F.CrtYd")
		)
		(fp_rect
			(start -0.5 -0.25)
			(end 0.5 0.25)
			(stroke
				(width 0.15)
				(type solid)
			)
			(fill none)
			(layer "F.Fab")
		)
		(fp_text user "Author: Antmicro"
			(at -0.95 4.169 180)
			(layer "F.Fab")
			(hide yes)
			(effects
				(font
					(size 0.7 0.7)
					(thickness 0.15)
				)
				(justify left bottom)
			)
		)
		(fp_text user "License: Apache-2.0"
			(at -0.95 5.169 180)
			(layer "F.Fab")
			(hide yes)
			(effects
				(font
					(size 0.7 0.7)
					(thickness 0.15)
				)
				(justify left bottom)
			)
		)
		(fp_text user "${REFERENCE}"
			(at -0.95 3.168 180)
			(layer "F.Fab")
			(hide yes)
			(effects
				(font
					(size 0.7 0.7)
					(thickness 0.15)
				)
				(justify left bottom)
			)
		)
		(pad "1" smd roundrect
			(at -0.48 0 180)
			(size 0.59 0.64)
			(layers "F.Cu" "F.Paste" "F.Mask")
			(roundrect_rratio 0.25)
			(net 316 "/USB3/USBC1_I_MODE")
			(pintype "passive")
		)
		(pad "2" smd roundrect
			(at 0.48 0 180)
			(size 0.59 0.64)
			(layers "F.Cu" "F.Paste" "F.Mask")
			(roundrect_rratio 0.25)
			(net 99 "+5V")
			(pintype "passive")
		)
	)
	(footprint "antmicro-footprints:C_0402_1005Metric"
		(layer "F.Cu")
		(at 76.6 111 -90)
		(descr "Capacitor SMD 0402")
		(tags "capacitor SMD 0402")
		(property "Reference" "C61"
			(at 2.95 -0.45 -90)
			(layer "F.SilkS")
			(effects
				(font
					(size 0.7 0.7)
					(thickness 0.15)
				)
				(justify left bottom)
			)
		)
		(property "Value" "C_100n_0402"
			(at 0 1.4 -90)
			(layer "F.Fab")
			(effects
				(font
					(size 0.7 0.7)
					(thickness 0.15)
				)
				(justify left bottom)
			)
		)
		(property "Footprint" "antmicro-footprints:C_0402_1005Metric"
			(at 0 0 -90)
			(layer "F.Fab")
			(hide yes)
			(effects
				(font
					(size 1.27 1.27)
					(thickness 0.15)
				)
			)
		)
		(property "Datasheet" "https://www.murata.com/products/productdetail?partno=GRM155R61H104KE14%23"
			(at 0 0 -90)
			(layer "F.Fab")
			(hide yes)
			(effects
				(font
					(size 1.27 1.27)
					(thickness 0.15)
				)
			)
		)
		(property "Author" "Antmicro"
			(at -34.4 187.6 0)
			(layer "F.Fab")
			(hide yes)
			(effects
				(font
					(size 1 1)
					(thickness 0.15)
				)
			)
		)
		(property "Dielectric" "X5R"
			(at -34.4 187.6 0)
			(layer "F.Fab")
			(hide yes)
			(effects
				(font
					(size 1 1)
					(thickness 0.15)
				)
			)
		)
		(property "License" "Apache-2.0"
			(at -34.4 187.6 0)
			(layer "F.Fab")
			(hide yes)
			(effects
				(font
					(size 1 1)
					(thickness 0.15)
				)
			)
		)
		(property "MPN" "GRM155R61H104KE14D"
			(at -34.4 187.6 0)
			(layer "F.Fab")
			(hide yes)
			(effects
				(font
					(size 1 1)
					(thickness 0.15)
				)
			)
		)
		(property "Manufacturer" "Murata"
			(at -34.4 187.6 0)
			(layer "F.Fab")
			(hide yes)
			(effects
				(font
					(size 1 1)
					(thickness 0.15)
				)
			)
		)
		(property "Val" "100n"
			(at -34.4 187.6 0)
			(layer "F.Fab")
			(hide yes)
			(effects
				(font
					(size 1 1)
					(thickness 0.15)
				)
			)
		)
		(property "Voltage" "50V"
			(at -34.4 187.6 0)
			(layer "F.Fab")
			(hide yes)
			(effects
				(font
					(size 1 1)
					(thickness 0.15)
				)
			)
		)
		(sheetname "USB Debug, DP")
		(sheetfile "usb.kicad_sch")
		(attr smd)
		(fp_rect
			(start -0.925 -0.47)
			(end 0.925 0.47)
			(stroke
				(width 0.05)
				(type default)
			)
			(fill none)
			(layer "F.CrtYd")
		)
		(fp_line
			(start -0.494 0.248)
			(end -0.494 -0.25)
			(stroke
				(width 0.15)
				(type solid)
			)
			(layer "F.Fab")
		)
		(fp_line
			(start 0.504 0.248)
			(end -0.494 0.248)
			(stroke
				(width 0.15)
				(type solid)
			)
			(layer "F.Fab")
		)
		(fp_line
			(start -0.494 -0.25)
			(end 0.504 -0.25)
			(stroke
				(width 0.15)
				(type solid)
			)
			(layer "F.Fab")
		)
		(fp_line
			(start 0.504 -0.25)
			(end 0.504 0.248)
			(stroke
				(width 0.15)
				(type solid)
			)
			(layer "F.Fab")
		)
		(fp_text user "${REFERENCE}"
			(at -0.932 3.168 -90)
			(layer "F.Fab")
			(hide yes)
			(effects
				(font
					(size 0.7 0.7)
					(thickness 0.15)
				)
				(justify left bottom)
			)
		)
		(fp_text user "License: Apache-2.0"
			(at -0.932 5.17 -90)
			(layer "F.Fab")
			(hide yes)
			(effects
				(font
					(size 0.7 0.7)
					(thickness 0.15)
				)
				(justify left bottom)
			)
		)
		(fp_text user "Author: Antmicro"
			(at -0.932 4.17 -90)
			(layer "F.Fab")
			(hide yes)
			(effects
				(font
					(size 0.7 0.7)
					(thickness 0.15)
				)
				(justify left bottom)
			)
		)
		(pad "1" smd roundrect
			(at -0.48 0 270)
			(size 0.59 0.64)
			(layers "F.Cu" "F.Paste" "F.Mask")
			(roundrect_rratio 0.25)
			(net 259 "/USB Debug, DP/USBC0_TX2_P")
			(pintype "passive")
		)
		(pad "2" smd roundrect
			(at 0.48 0 270)
			(size 0.59 0.64)
			(layers "F.Cu" "F.Paste" "F.Mask")
			(roundrect_rratio 0.25)
			(net 260 "/USB Debug, DP/USBC0_CONN_TX2_P")
			(pintype "passive")
		)
	)
	(footprint "antmicro-footprints:C_0603_1608Metric_EIA"
		(layer "F.Cu")
		(at 72.575 91.67 -90)
		(descr "Capacitor SMD 0603, IPC-7351 Density Level A")
		(tags "Capacitor 0603")
		(property "Reference" "C128"
			(at -6.406396 -14.09 -90)
			(layer "F.SilkS")
			(effects
				(font
					(size 0.7 0.7)
					(thickness 0.15)
				)
				(justify left bottom)
			)
		)
		(property "Value" "C_22u_16V_0603"
			(at -1.42757 1.770288 -90)
			(layer "F.Fab")
			(effects
				(font
					(size 0.7 0.7)
					(thickness 0.15)
				)
				(justify left bottom)
			)
		)
		(property "Footprint" "antmicro-footprints:C_0603_1608Metric_EIA"
			(at 0 0 -90)
			(layer "F.Fab")
			(hide yes)
			(effects
				(font
					(size 1.27 1.27)
					(thickness 0.15)
				)
			)
		)
		(property "Datasheet" "https://product.samsungsem.com/mlcc/CL10A226MO7JZN.do"
			(at 0 0 -90)
			(layer "F.Fab")
			(hide yes)
			(effects
				(font
					(size 1.27 1.27)
					(thickness 0.15)
				)
			)
		)
		(property "Description" "SMD Multilayer Ceramic Capacitor"
			(at 0 0 -90)
			(layer "F.Fab")
			(hide yes)
			(effects
				(font
					(size 1.27 1.27)
					(thickness 0.15)
				)
			)
		)
		(property "Manufacturer" "Samsung Electro-Mechanics"
			(at 0 0 -90)
			(unlocked yes)
			(layer "F.Fab")
			(hide yes)
			(effects
				(font
					(size 1 1)
					(thickness 0.15)
				)
			)
		)
		(property "MPN" "CL10A226MO7JZNC"
			(at 0 0 -90)
			(unlocked yes)
			(layer "F.Fab")
			(hide yes)
			(effects
				(font
					(size 1 1)
					(thickness 0.15)
				)
			)
		)
		(property "Val" "22u"
			(at 0 0 -90)
			(unlocked yes)
			(layer "F.Fab")
			(hide yes)
			(effects
				(font
					(size 1 1)
					(thickness 0.15)
				)
			)
		)
		(property "License" "Apache-2.0"
			(at 0 0 -90)
			(unlocked yes)
			(layer "F.Fab")
			(hide yes)
			(effects
				(font
					(size 1 1)
					(thickness 0.15)
				)
			)
		)
		(property "Author" "Antmicro"
			(at 0 0 -90)
			(unlocked yes)
			(layer "F.Fab")
			(hide yes)
			(effects
				(font
					(size 1 1)
					(thickness 0.15)
				)
			)
		)
		(property "Voltage" "16V"
			(at 0 0 -90)
			(unlocked yes)
			(layer "F.Fab")
			(hide yes)
			(effects
				(font
					(size 1 1)
					(thickness 0.15)
				)
			)
		)
		(property "Dielectric" ""
			(at 0 0 -90)
			(unlocked yes)
			(layer "F.Fab")
			(hide yes)
			(effects
				(font
					(size 1 1)
					(thickness 0.15)
				)
			)
		)
		(sheetname "Supply")
		(sheetfile "supply.kicad_sch")
		(attr smd)
		(fp_line
			(start -0.15 0.55)
			(end 0.15 0.55)
			(stroke
				(width 0.15)
				(type solid)
			)
			(layer "F.SilkS")
		)
		(fp_line
			(start -0.15 -0.55)
			(end 0.15 -0.55)
			(stroke
				(width 0.15)
				(type solid)
			)
			(layer "F.SilkS")
		)
		(fp_rect
			(start -1.25 -0.65)
			(end 1.25 0.65)
			(stroke
				(width 0.05)
				(type solid)
			)
			(fill none)
			(layer "F.CrtYd")
		)
		(fp_rect
			(start -0.8 -0.45)
			(end 0.8 0.45)
			(stroke
				(width 0.15)
				(type solid)
			)
			(fill none)
			(layer "F.Fab")
		)
		(fp_text user "License: Apache-2.0"
			(at -1.682 5.895 -90)
			(layer "F.Fab")
			(hide yes)
			(effects
				(font
					(size 0.7 0.7)
					(thickness 0.15)
				)
				(justify left bottom)
			)
		)
		(fp_text user "Author: Antmicro"
			(at -1.682 4.894 -90)
			(layer "F.Fab")
			(hide yes)
			(effects
				(font
					(size 0.7 0.7)
					(thickness 0.15)
				)
				(justify left bottom)
			)
		)
		(fp_text user "${REFERENCE}"
			(at -1.682 3.895 -90)
			(layer "F.Fab")
			(hide yes)
			(effects
				(font
					(size 0.7 0.7)
					(thickness 0.15)
				)
				(justify left bottom)
			)
		)
		(pad "1" smd roundrect
			(at -0.7 0 270)
			(size 0.8 1.1)
			(layers "F.Cu" "F.Paste" "F.Mask")
			(roundrect_rratio 0.2)
			(net 1 "GND")
			(pintype "passive")
		)
		(pad "2" smd roundrect
			(at 0.7 0 270)
			(size 0.8 1.1)
			(layers "F.Cu" "F.Paste" "F.Mask")
			(roundrect_rratio 0.2)
			(net 641 "/Supply/3V3_OUT")
			(pintype "passive")
		)
	)
)
